# T6G (Grand Teton) — schematic netlist excerpt (pin names and nets, part order shuffled) for the footprints in the layout excerpt that follows; sources: Cadence DE-HDL packaged netlist, KiCad conversion of 04192023_DAF0TMB3IC0_F0TG_MB_C_brd_V02_OCP.brd

R1673  Q_RES  10K 1% CHIP  pkg 0402LF  page 145 : A = P3V3_E1S_0 ; B = RST_SMB_E1S_0_N

PR2534  Q_SP_RES4P  0.0003 1% CHIP  pkg R2725_4P  page 266
  \1a\  = P12V_PSU
  \1b\  = P12V_HSC_SENSE2_R4_P
  \2a\  = P12V_MAIN_R
  \2b\  = P12V_HSC_SENSE2_R4_N

PC6500  Q_CAP  0.1UF 25V 10% X6S  pkg C0402  page 360 : A = P12V_AUX ; B = GND

(kicad_pcb
	(version 20260206)
	(generator "pcbnew")
	(generator_version "10.0")
	(general
		(thickness 1.6)
		(legacy_teardrops no)
	)
	(paper "A4")
	(title_block
		(title "04192023_DAF0TMB3IC0_F0TG_MB_C_brd_V02_OCP.brd")
		(comment 1 "Grand Teton / footprints 3853-3855 of 8354")
	)
	(layers
		(0 "F.Cu" signal "TOP")
		(4 "In1.Cu" signal "GND")
		(6 "In2.Cu" signal "IN1")
		(8 "In3.Cu" signal "GND1")
		(10 "In4.Cu" signal "IN2")
		(12 "In5.Cu" signal "GND2")
		(14 "In6.Cu" signal "IN3")
		(16 "In7.Cu" signal "GND3")
		(18 "In8.Cu" signal "VCC")
		(20 "In9.Cu" signal "VCC1")
		(22 "In10.Cu" signal "GND4")
		(24 "In11.Cu" signal "IN4")
		(26 "In12.Cu" signal "GND5")
		(28 "In13.Cu" signal "IN5")
		(30 "In14.Cu" signal "GND6")
		(32 "In15.Cu" signal "IN6")
		(34 "In16.Cu" signal "GND7")
		(2 "B.Cu" signal "BOTTOM")
		(9 "F.Adhes" user "F.Adhesive")
		(11 "B.Adhes" user "B.Adhesive")
		(13 "F.Paste" user "Package Geometry/Pastemask Top")
		(15 "B.Paste" user "Package Geometry/Pastemask Bottom")
		(5 "F.SilkS" user "Ref Des/Silkscreen Top")
		(7 "B.SilkS" user "Ref Des/Silkscreen Bottom")
		(1 "F.Mask" user "Board Geometry/Soldermask Top")
		(3 "B.Mask" user "Board Geometry/Soldermask Bottom")
		(17 "Dwgs.User" user "User.Drawings")
		(19 "Cmts.User" user "User.Comments")
		(21 "Eco1.User" user "User.Eco1")
		(23 "Eco2.User" user "User.Eco2")
		(25 "Edge.Cuts" user "Board Geometry/Outline")
		(27 "Margin" user)
		(31 "F.CrtYd" user "Package Geometry/Place Bound Top")
		(29 "B.CrtYd" user "Package Geometry/Place Bound Bottom")
		(35 "F.Fab" user "Ref Des/Assembly Top")
		(33 "B.Fab" user "Ref Des/Assembly Bottom")
	)
	(footprint ""
		(layer "F.Cu")
		(at 248.59615 -268.092936 180)
		(property "Reference" "PC6500"
			(at 0 0 180)
			(layer "F.SilkS")
			(hide yes)
			(effects
				(font
					(size 1.27 1.27)
				)
			)
		)
		(property "Value" ""
			(at 0 0 180)
			(layer "F.Fab")
			(effects
				(font
					(size 1.27 1.27)
				)
			)
		)
		(duplicate_pad_numbers_are_jumpers no)
		(fp_line
			(start 0.7874 0.4064)
			(end -0.7874 0.4064)
			(stroke
				(width 0.1524)
				(type default)
			)
			(layer "F.SilkS")
		)
		(fp_line
			(start 0.7874 -0.4064)
			(end 0.7874 0.4064)
			(stroke
				(width 0.1524)
				(type default)
			)
			(layer "F.SilkS")
		)
		(fp_line
			(start -0.7874 0.4064)
			(end -0.7874 -0.4064)
			(stroke
				(width 0.1524)
				(type default)
			)
			(layer "F.SilkS")
		)
		(fp_line
			(start -0.7874 -0.4064)
			(end 0.7874 -0.4064)
			(stroke
				(width 0.1524)
				(type default)
			)
			(layer "F.SilkS")
		)
		(fp_line
			(start 0.67945 0.3048)
			(end 0.120396 0.3048)
			(stroke
				(width 0.1)
				(type default)
			)
			(layer "F.Fab")
		)
		(fp_line
			(start 0.67945 -0.3048)
			(end 0.67945 0.3048)
			(stroke
				(width 0.1)
				(type default)
			)
			(layer "F.Fab")
		)
		(fp_line
			(start 0.12065 -0.2794)
			(end 0.12065 -0.3048)
			(stroke
				(width 0.1)
				(type default)
			)
			(layer "F.Fab")
		)
		(fp_line
			(start 0.12065 -0.3048)
			(end 0.67945 -0.3048)
			(stroke
				(width 0.1)
				(type default)
			)
			(layer "F.Fab")
		)
		(fp_line
			(start 0.120396 0.3048)
			(end 0.120396 0.2794)
			(stroke
				(width 0.1)
				(type default)
			)
			(layer "F.Fab")
		)
		(fp_line
			(start 0.120396 0.2794)
			(end -0.12065 0.2794)
			(stroke
				(width 0.1)
				(type default)
			)
			(layer "F.Fab")
		)
		(fp_line
			(start -0.12065 0.3048)
			(end -0.67945 0.3048)
			(stroke
				(width 0.1)
				(type default)
			)
			(layer "F.Fab")
		)
		(fp_line
			(start -0.12065 0.2794)
			(end -0.12065 0.3048)
			(stroke
				(width 0.1)
				(type default)
			)
			(layer "F.Fab")
		)
		(fp_line
			(start -0.12065 -0.2794)
			(end 0.12065 -0.2794)
			(stroke
				(width 0.1)
				(type default)
			)
			(layer "F.Fab")
		)
		(fp_line
			(start -0.12065 -0.305054)
			(end -0.12065 -0.2794)
			(stroke
				(width 0.1)
				(type default)
			)
			(layer "F.Fab")
		)
		(fp_line
			(start -0.67945 0.3048)
			(end -0.67945 -0.305054)
			(stroke
				(width 0.1)
				(type default)
			)
			(layer "F.Fab")
		)
		(fp_line
			(start -0.67945 -0.305054)
			(end -0.12065 -0.305054)
			(stroke
				(width 0.1)
				(type default)
			)
			(layer "F.Fab")
		)
		(pad "1" smd circle
			(at -0.40005 0 180)
			(size 0 0)
			(layers "F.Cu" "F.Mask" "F.Paste")
			(net "P12V_AUX")
		)
		(pad "2" smd circle
			(at 0.40005 0 180)
			(size 0 0)
			(layers "F.Cu" "F.Mask" "F.Paste")
			(net "GND")
		)
	)
	(footprint ""
		(layer "F.Cu")
		(at 224.20961 -46.524926)
		(property "Reference" "R1673"
			(at 0 0 0)
			(layer "F.SilkS")
			(hide yes)
			(effects
				(font
					(size 1.27 1.27)
				)
			)
		)
		(property "Value" ""
			(at 0 0 0)
			(layer "F.Fab")
			(effects
				(font
					(size 1.27 1.27)
				)
			)
		)
		(duplicate_pad_numbers_are_jumpers no)
		(fp_line
			(start -0.7874 -0.4064)
			(end 0.7874 -0.4064)
			(stroke
				(width 0.1524)
				(type default)
			)
			(layer "F.SilkS")
		)
		(fp_line
			(start -0.7874 0.4064)
			(end -0.7874 -0.4064)
			(stroke
				(width 0.1524)
				(type default)
			)
			(layer "F.SilkS")
		)
		(fp_line
			(start 0.7874 -0.4064)
			(end 0.7874 0.4064)
			(stroke
				(width 0.1524)
				(type default)
			)
			(layer "F.SilkS")
		)
		(fp_line
			(start 0.7874 0.4064)
			(end -0.7874 0.4064)
			(stroke
				(width 0.1524)
				(type default)
			)
			(layer "F.SilkS")
		)
		(fp_line
			(start -0.67945 -0.305054)
			(end -0.12065 -0.305054)
			(stroke
				(width 0.1)
				(type default)
			)
			(layer "F.Fab")
		)
		(fp_line
			(start -0.67945 0.3048)
			(end -0.67945 -0.305054)
			(stroke
				(width 0.1)
				(type default)
			)
			(layer "F.Fab")
		)
		(fp_line
			(start -0.12065 -0.305054)
			(end -0.12065 -0.2794)
			(stroke
				(width 0.1)
				(type default)
			)
			(layer "F.Fab")
		)
		(fp_line
			(start -0.12065 -0.2794)
			(end 0.12065 -0.2794)
			(stroke
				(width 0.1)
				(type default)
			)
			(layer "F.Fab")
		)
		(fp_line
			(start -0.12065 0.2794)
			(end -0.12065 0.3048)
			(stroke
				(width 0.1)
				(type default)
			)
			(layer "F.Fab")
		)
		(fp_line
			(start -0.12065 0.3048)
			(end -0.67945 0.3048)
			(stroke
				(width 0.1)
				(type default)
			)
			(layer "F.Fab")
		)
		(fp_line
			(start 0.120396 0.2794)
			(end -0.12065 0.2794)
			(stroke
				(width 0.1)
				(type default)
			)
			(layer "F.Fab")
		)
		(fp_line
			(start 0.120396 0.3048)
			(end 0.120396 0.2794)
			(stroke
				(width 0.1)
				(type default)
			)
			(layer "F.Fab")
		)
		(fp_line
			(start 0.12065 -0.3048)
			(end 0.67945 -0.3048)
			(stroke
				(width 0.1)
				(type default)
			)
			(layer "F.Fab")
		)
		(fp_line
			(start 0.12065 -0.2794)
			(end 0.12065 -0.3048)
			(stroke
				(width 0.1)
				(type default)
			)
			(layer "F.Fab")
		)
		(fp_line
			(start 0.67945 -0.3048)
			(end 0.67945 0.3048)
			(stroke
				(width 0.1)
				(type default)
			)
			(layer "F.Fab")
		)
		(fp_line
			(start 0.67945 0.3048)
			(end 0.120396 0.3048)
			(stroke
				(width 0.1)
				(type default)
			)
			(layer "F.Fab")
		)
		(pad "1" smd circle
			(at -0.40005 0)
			(size 0 0)
			(layers "F.Cu" "F.Mask" "F.Paste")
			(net "P3V3_E1S_0")
		)
		(pad "2" smd circle
			(at 0.40005 0)
			(size 0 0)
			(layers "F.Cu" "F.Mask" "F.Paste")
			(net "RST_SMB_E1S_0_N")
		)
	)
	(footprint ""
		(layer "F.Cu")
		(at 260.171184 -393.91336 -90)
		(property "Reference" "PR2534"
			(at -4.64312 3.085084 90)
			(unlocked yes)
			(layer "F.SilkS")
			(effects
				(font
					(size 0.7874 0.5842)
					(thickness 0.1524)
				)
				(justify left)
			)
		)
		(property "Value" ""
			(at 0 0 270)
			(layer "F.Fab")
			(effects
				(font
					(size 1.27 1.27)
				)
			)
		)
		(duplicate_pad_numbers_are_jumpers no)
		(fp_line
			(start -3.9878 3.5814)
			(end -3.9878 -3.5814)
			(stroke
				(width 0.1524)
				(type default)
			)
			(layer "F.SilkS")
		)
		(fp_line
			(start 3.9878 3.5814)
			(end -3.9878 3.5814)
			(stroke
				(width 0.1524)
				(type default)
			)
			(layer "F.SilkS")
		)
		(fp_line
			(start -3.9878 -3.5814)
			(end 3.9878 -3.5814)
			(stroke
				(width 0.1524)
				(type default)
			)
			(layer "F.SilkS")
		)
		(fp_line
			(start 3.9878 -3.5814)
			(end 3.9878 3.5814)
			(stroke
				(width 0.1524)
				(type default)
			)
			(layer "F.SilkS")
		)
		(fp_line
			(start -3.5306 3.353054)
			(end -3.5306 -3.353054)
			(stroke
				(width 0.1)
				(type default)
			)
			(layer "F.Fab")
		)
		(fp_line
			(start 3.5306 3.353054)
			(end -3.5306 3.353054)
			(stroke
				(width 0.1)
				(type default)
			)
			(layer "F.Fab")
		)
		(fp_line
			(start -3.5306 -3.353054)
			(end 3.5306 -3.353054)
			(stroke
				(width 0.1)
				(type default)
			)
			(layer "F.Fab")
		)
		(fp_line
			(start 3.5306 -3.353054)
			(end 3.5306 3.353054)
			(stroke
				(width 0.1)
				(type default)
			)
			(layer "F.Fab")
		)
		(pad "1A" smd rect
			(at -2.249932 0 90)
			(size 3.2004 6.858)
			(layers "F.Cu" "F.Mask" "F.Paste")
			(net "P12V_PSU")
		)
		(pad "1B" smd rect
			(at -0.776732 0 270)
			(size 0.254 0.508)
			(layers "F.Cu" "F.Mask" "F.Paste")
			(net "P12V_HSC_SENSE2_R4_P")
		)
		(pad "2A" smd rect
			(at 2.249932 0 90)
			(size 3.2004 6.858)
			(layers "F.Cu" "F.Mask" "F.Paste")
			(net "P12V_MAIN_R")
		)
		(pad "2B" smd rect
			(at 0.776732 0 270)
			(size 0.254 0.508)
			(layers "F.Cu" "F.Mask" "F.Paste")
			(net "P12V_HSC_SENSE2_R4_N")
		)
	)
)
